FILE_TYPE = CONNECTIVITY;
{Allegro Design Entry HDL 16.6-p007 (v16-6-112F) 10/10/2012}
"PAGE_NUMBER" = 202;
0"NC";
1"GND\g";
2"PVCCIN_CPU0\g";
3"GND\g";
4"GND\g";
5"PVCCIN_CPU0\g";
6"VR_FET_SW_P12V_STBY_PVCCIN_CPU0\g";
7"GND\g";
8"VR_FET_SW_P12V_STBY_PVCCIN_CPU0\g";
9"GND\g";
10"P5V_STBY\g";
11"P5V_STBY\g";
12"GND\g";
13"GND\g";
14"GND\g";
15"GND\g";
16"GND\g";
17"GND\g";
18"GND\g";
19"GND\g";
20"VR_PVCCIN_CPU0_PHASE2"VOLTAGE"5";
21"VR_PVCCIN_CPU0_PWM2";
22"VR_PVCCIN_CPU0_AIREF2";
23"TP_PVCCIN_CPU0_PH2_GL_0";
24"TP_PVCCIN_CPU0_PH2_GL_1";
25"VR_PVCCIN_CPU0_PH2_PHASE"VOLTAGE"5";
26"VR_PVCCIN_CPU0_PH2_BOOT";
27"VR_PVCCIN_CPU0_PH2_VCIN"VOLTAGE"5";
28"VR_PVCCIN_CPU0_PWM1";
29"VR_PVCCIN_CPU0_PH1_PHASE"VOLTAGE"5";
30"ISENSE_PVCCIN_CPU0_PH2_IMON";
31"VR_PVCCIN_CPU0_AIREF1";
32"VR_PVCCIN_CPU0_PH1_BOOT";
33"VR_PVCCIN_CPU0_PH1_BOOT_R";
34"VR_PVCCIN_CPU0_PH1_VCIN"VOLTAGE"5";
35"VR_PVCCIN_CPU0_PHASE1"VOLTAGE"5";
36"VR_PVCCIN_CPU0_PHASE2_RC";
37"VR_PVCCIN_CPU0_PHASE1_RC";
38"TP_PVCCIN_CPU0_PH1_GL_1";
39"A_TSENSE_PVCCIN_CPU0";
40"ISENSE_PVCCIN_CPU0_PH1_IMON";
41"VR_PVCCIN_CPU0_PH1_OCSET";
42"TP_PVCCIN_CPU0_PH1_GL_0";
43"VR_PVCCIN_CPU0_PH2_BOOT_R";
44"A_TSENSE_PVCCIN_CPU0";
45"VR_PVCCIN_CPU0_PH2_OCSET"VOLTAGE"3.6";
46"GND\g";
%"RES"
"1","(-5025,3575)","0","mstr_discrete","I101";
;
CDS_SEC"1"
CDS_LOCATION"RT1"
MATERIAL"CHIP"
WATTAGE"1/10W"
LOCATION"RT1"
PACK_TYPE"0603"
VALUE"0"
PART_NUMBER"G22178-002"
TOLERANCE"5.0%"
SEC"1"
SEC_TYPE"0603"
CDS_LIB"mstr_discrete"
BOM_COST"NT_GBE_BASE"
ROOM"NIC_SPRV";
"B"
$PN"2"33;
"A"
$PN"1"32;
%"RES"
"1","(-5025,950)","0","mstr_discrete","I102";
;
CDS_SEC"1"
CDS_LOCATION"RT3"
PART_NUMBER"G22178-002"
TOLERANCE"5.0%"
LOCATION"RT3"
PACK_TYPE"0603"
WATTAGE"1/10W"
MATERIAL"CHIP"
VALUE"0"
SEC_TYPE"0603"
SEC"1"
CDS_LIB"mstr_discrete"
BOM_COST"NT_GBE_BASE"
ROOM"NIC_SPRV";
"B"
$PN"2"43;
"A"
$PN"1"26;
%"RES"
"1","(-5550,4625)","0","mstr_discrete","I107";
;
VALUE"0.0"
TOLERANCE"5%"
PART_NUMBER"G21497-005"
LOCATION"R6R2"
WATTAGE"1/16W"
MATERIAL"CHIP"
PACK_TYPE"0402"
CDS_LOCATION"R6R2"
CDS_SEC"1"
ROOM"CPU0"
SEC"1"
SEC_TYPE"0402"
CDS_LIB"mstr_discrete"
BOM_COST"PROC_SIDEBAND";
"B"
$PN"2"11;
"A"
$PN"1"34;
%"RES"
"1","(-5625,1975)","0","mstr_discrete","I108";
;
VALUE"0.0"
PACK_TYPE"0402"
LOCATION"R6R6"
PART_NUMBER"G21497-005"
TOLERANCE"5%"
WATTAGE"1/16W"
MATERIAL"CHIP"
CDS_LOCATION"R6R6"
BOM_COST"PROC_SIDEBAND"
CDS_LIB"mstr_discrete"
SEC_TYPE"0402"
SEC"1"
ROOM"CPU0"
CDS_SEC"1";
"B"
$PN"2"10;
"A"
$PN"1"27;
%"IND-120NH-30-GP"
"1","(-1700,3525)","1","w_hdl","I109";
;
CDS_SEC"1"
CDS_LOCATION"L4E1"
TYPE"IRMS=66A@DELTA_T<40C"
PACK_SIZE"DCR=0.17MOHM"
RATED"ISAT=94A@25C"
ATTRIBUTE"120NH"
LOCATION"L4E1"
VALUE"IND-120NH-30-GP"
PART_NUMBER"068.1202N.M001"
CDS_LIB"w_hdl"
CDS_LMAN_SYM_OUTLINE"-75,100,75,-100"
SEC_TYPE"DISCRET-GB2"
SEC"1"
PACK_TYPE"DISCRET-GB2";
"F"
$PN"2"5;
"S"
$PN"1"35;
%"IND-120NH-30-GP"
"1","(-1300,975)","1","w_hdl","I110";
;
CDS_SEC"1"
CDS_LOCATION"L4D3"
TYPE"IRMS=66A@DELTA_T<40C"
PACK_SIZE"DCR=0.17MOHM"
RATED"ISAT=94A@25C"
ATTRIBUTE"120NH"
VALUE"IND-120NH-30-GP"
LOCATION"L4D3"
PART_NUMBER"068.1202N.M001"
CDS_LIB"w_hdl"
CDS_LMAN_SYM_OUTLINE"-75,100,75,-100"
SEC_TYPE"DISCRET-GB2"
SEC"1"
PACK_TYPE"DISCRET-GB2";
"F"
$PN"2"2;
"S"
$PN"1"20;
%"SC1U10V2KX-4-GP"
"1","(-5275,1425)","0","w_hdl","I111";
;
CDS_SEC"1"
CDS_LOCATION"C4E25"
ATTRIBUTE"1UF"
TOLERANCE"10%"
VALUE"SC1U10V2KX-4-GP"
PACK_SIZE"0402"
RATED"10V"
LOCATION"C4E25"
PACK_TYPE"SMD-BCG6"
SEC"1"
SEC_TYPE"SMD-BCG6"
PART_NUMBER"78.10523.8FL"
CDS_LIB"w_hdl"
CDS_LMAN_SYM_OUTLINE"-50,25,50,-25";
"2"
$PN"2"9;
"1"
$PN"1"10;
%"SC1U10V2KX-4-GP"
"1","(-5275,4075)","0","w_hdl","I112";
;
CDS_SEC"1"
CDS_LOCATION"C4E6"
RATED"10V"
TOLERANCE"10%"
ATTRIBUTE"1UF"
LOCATION"C4E6"
VALUE"SC1U10V2KX-4-GP"
PACK_SIZE"0402"
PACK_TYPE"SMD-BCG6"
SEC"1"
SEC_TYPE"SMD-BCG6"
PART_NUMBER"78.10523.8FL"
CDS_LIB"w_hdl"
CDS_LMAN_SYM_OUTLINE"-50,25,50,-25";
"2"
$PN"2"7;
"1"
$PN"1"11;
%"1R3F-GP"
"1","(-2550,2950)","0","w_hdl","I114";
;
CDS_SEC"1"
CDS_LOCATION"RT2"
POP"NOPOP"
TOLERANCE"1%"
LOCATION"RT2"
ATTRIBUTE"1 OHM"
VALUE"1R3F-GP"
RATED"1/10W"
PACK_SIZE"0603"
PACK_TYPE"RCL_GP"
SEC"1"
SEC_TYPE"RCL_GP"
PART_NUMBER"64.1R005.55L"
CDS_LIB"w_hdl"
CDS_LMAN_SYM_OUTLINE"-50,75,50,-75";
"2"
$PN"2"16;
"1"
$PN"1"37;
%"1R3F-GP"
"1","(-2550,525)","0","w_hdl","I115";
;
CDS_SEC"1"
CDS_LOCATION"RT4"
POP"NOPOP"
TOLERANCE"1%"
LOCATION"RT4"
VALUE"1R3F-GP"
ATTRIBUTE"1 OHM"
RATED"1/10W"
PACK_SIZE"0603"
CDS_LMAN_SYM_OUTLINE"-50,75,50,-75"
CDS_LIB"w_hdl"
PART_NUMBER"64.1R005.55L"
SEC_TYPE"RCL_GP"
SEC"1"
PACK_TYPE"RCL_GP";
"2"
$PN"2"46;
"1"
$PN"1"36;
%"GND"
"1","(-2800,3125)","0","mstr_symbols","I13";
;
CDS_LIB"mstr_symbols"
ROOM"PVCCIN_CPU0_PWR_VR"
BOM_COST"PROC_VRD_VCCIN_CPU0"
VOLTAGE"0"
SIZE"1B"
BODY_TYPE"PLUMBING"
HDL_POWER"GND";
"A\NAC"1;
%"CAP"
"1","(-4900,4125)","0","mstr_discrete","I18";
;
CDS_SEC"1"
LOCATION"C4E5"
VALUE"0.22UF"
VOLTAGE"16V"
TOLERANCE"10%"
MATERIAL"X7R"
PART_NUMBER"A36096-155"
PACK_TYPE"0402"
ROOM"PVCCIN_CPU0_PWR_VR"
CDS_LOCATION"C4E5"
SEC"1"
SEC_TYPE"0402"
CDS_LIB"mstr_discrete";
"A"
$PN"1"11;
"B"
$PN"2"7;
%"CAP"
"1","(-5850,3450)","2","mstr_discrete","I22";
;
CDS_SEC"1"
VALUE"0.220UF"
TOLERANCE"10%"
VOLTAGE"16V"
LOCATION"C4E17"
MATERIAL"X7R"
PACK_TYPE"0402"
PART_NUMBER"A36096-104"
CDS_LOCATION"C4E17"
CDS_LIB"mstr_discrete"
SEC_TYPE"0402"
SPOF"TRUE"
SEC"1"
NO_XNET_CONNECTION"1"
ROOM"PVCCIN_CPU0_PWR_VR";
"A"
$PN"1"32;
"B"
$PN"2"29;
%"CAP"
"1","(-4950,1425)","0","mstr_discrete","I24";
;
CDS_SEC"1"
CDS_LOCATION"C4E27"
LOCATION"C4E27"
VALUE"0.22UF"
VOLTAGE"16V"
PART_NUMBER"A36096-155"
MATERIAL"X7R"
TOLERANCE"10%"
PACK_TYPE"0402"
ROOM"PVCCIN_CPU0_PWR_VR"
SEC"1"
SEC_TYPE"0402"
CDS_LIB"mstr_discrete";
"A"
$PN"1"10;
"B"
$PN"2"9;
%"PVCCIN_CPU0"
"1","(-500,1050)","0","mstr_symbols","I26";
;
VOLTAGE"2.0V"
CDS_LIB"mstr_symbols"
BODY_TYPE"PLUMBING"
HDL_POWER"PVCCIN_CPU0";
"G\NAC"2;
%"CAP_A"
"1","(-850,750)","0","dev_discrete","I27";
;
GROUP"PWR_MLCC_CAP"
TOLERANCE"20%"
VOLTAGE"4V"
LOCATION"C4E11"
VALUE"22.0UF"
MATERIAL"X6S"
PART_NUMBER"E15431-004"
PACK_TYPE"0603V"
SEC"1"
SEC_TYPE"0603V"
CDS_LOCATION"C4E11"
BOM_COST"PROC_VRD_VCCIN_CPU0"
CDS_SEC"1"
ROOM"PVCCIN_CPU0_PWR_VR"
CDS_LIB"dev_discrete";
"B"
$PN"2"3;
"A"
$PN"1"2;
%"GND"
"1","(-500,475)","0","mstr_symbols","I28";
;
HDL_POWER"GND"
BODY_TYPE"PLUMBING"
ROOM"PVCCIN_CPU0_PWR_VR"
BOM_COST"PROC_VRD_VCCIN_CPU0"
SIZE"1B"
CDS_LIB"mstr_symbols"
VOLTAGE"0";
"A\NAC"3;
%"GND"
"1","(-2800,525)","0","mstr_symbols","I30";
;
ROOM"PVCCIN_CPU0_PWR_VR"
BOM_COST"PROC_VRD_VCCIN_CPU0"
SIZE"1B"
VOLTAGE"0"
CDS_LIB"mstr_symbols"
BODY_TYPE"PLUMBING"
HDL_POWER"GND";
"A\NAC"4;
%"CAP"
"1","(-5950,825)","2","mstr_discrete","I32";
;
CDS_SEC"1"
CDS_LOCATION"C4D50"
PART_NUMBER"A36096-104"
PACK_TYPE"0402"
LOCATION"C4D50"
VALUE"0.220UF"
VOLTAGE"16V"
TOLERANCE"10%"
MATERIAL"X7R"
NO_XNET_CONNECTION"1"
SEC"1"
SPOF"TRUE"
SEC_TYPE"0402"
ROOM"PVCCIN_CPU0_PWR_VR"
CDS_LIB"mstr_discrete";
"A"
$PN"1"26;
"B"
$PN"2"25;
%"CAP"
"1","(-5700,4025)","0","mstr_discrete","I34";
;
CDS_SEC"1"
MATERIAL"X6S"
LOCATION"C4E10"
VALUE"1.0UF"
VOLTAGE"16V"
TOLERANCE"10%"
PACK_TYPE"0402"
PART_NUMBER"D97712-011"
ROOM"PVCCIN_CPU0_PWR_VR"
CDS_LOCATION"C4E10"
SEC"1"
SEC_TYPE"0402"
CDS_LIB"mstr_discrete";
"A"
$PN"1"34;
"B"
$PN"2"7;
%"CAP_A"
"1","(-5975,4050)","0","dev_discrete","I35";
;
LOCATION"C4E20"
VALUE"0.1UF"
VOLTAGE"16V"
TOLERANCE"10%"
MATERIAL"X7R"
PART_NUMBER"A36096-030"
PACK_TYPE"0402V"
CDS_LOCATION"C4E20"
CDS_SEC"1"
CDS_LIB"dev_discrete"
SEC_TYPE"0402V"
SEC"1"
ROOM"PVCCIN_CPU0_PWR_VR";
"B"
$PN"2"7;
"A"
$PN"1"6;
%"CAP"
"1","(-6250,4075)","0","mstr_discrete","I36";
;
CDS_SEC"1"
TOLERANCE"10%"
VOLTAGE"16V"
MATERIAL"X6S"
VALUE"1.0UF"
LOCATION"C4E19"
PACK_TYPE"0402"
PART_NUMBER"D97712-011"
CDS_LIB"mstr_discrete"
ROOM"PVCCIN_CPU0_PWR_VR"
CDS_LOCATION"C4E19"
SEC"1"
SEC_TYPE"0402";
"A"
$PN"1"6;
"B"
$PN"2"7;
%"CAP"
"1","(-6550,4075)","0","mstr_discrete","I37";
;
CDS_SEC"1"
TOLERANCE"10%"
VOLTAGE"16V"
PART_NUMBER"C95333-007"
MATERIAL"X6S"
VALUE"10UF"
LOCATION"C6R11"
PACK_TYPE"0805"
SEC_TYPE"0805"
SEC"1"
CDS_LOCATION"C6R11"
ROOM"PVCCIN_CPU0_PWR_VR"
CDS_LIB"mstr_discrete";
"A"
$PN"1"6;
"B"
$PN"2"7;
%"CAP"
"1","(-6825,4075)","0","mstr_discrete","I38";
;
CDS_SEC"1"
TOLERANCE"10%"
VOLTAGE"16V"
PACK_TYPE"0805"
VALUE"10UF"
MATERIAL"X6S"
LOCATION"C6P13"
PART_NUMBER"C95333-007"
CDS_LIB"mstr_discrete"
SEC_TYPE"0805"
CDS_LOCATION"C6P13"
SEC"1"
ROOM"PVCCIN_CPU0_PWR_VR";
"A"
$PN"1"6;
"B"
$PN"2"7;
%"PVCCIN_CPU0"
"1","(-650,3600)","0","mstr_symbols","I4";
;
HDL_POWER"PVCCIN_CPU0"
BODY_TYPE"PLUMBING"
ROOM"PVCCIN_CPU0_PWR_VR"
CDS_LIB"mstr_symbols"
BOM_COST"PROC_SOCKET "
VOLTAGE"2.0V";
"G\NAC"5;
%"VCC_CORE"
"1","(-6600,4500)","0","mstr_symbols","I41";
;
HDL_POWER"VR_FET_SW_P12V_STBY_PVCCIN_CPU0"
CDS_LIB"mstr_symbols";
"A"6;
%"CAP"
"1","(-7100,4075)","0","mstr_discrete","I42";
;
CDS_SEC"1"
PACK_TYPE"0805"
MATERIAL"X6S"
LOCATION"C6R13"
PART_NUMBER"C95333-007"
VOLTAGE"16V"
VALUE"10UF"
TOLERANCE"10%"
CDS_LIB"mstr_discrete"
ROOM"PVCCIN_CPU0_PWR_VR"
CDS_LOCATION"C6R13"
SEC"1"
SEC_TYPE"0805";
"A"
$PN"1"6;
"B"
$PN"2"7;
%"GND"
"1","(-7100,3525)","0","mstr_symbols","I43";
;
ROOM"PVCCIN_CPU0_PWR_VR"
VOLTAGE"0"
CDS_LIB"mstr_symbols"
BOM_COST"PROC_VRD_VCCIN_CPU0"
SIZE"1B"
BODY_TYPE"PLUMBING"
HDL_POWER"GND";
"A\NAC"7;
%"VCC_CORE"
"1","(-6725,1875)","0","mstr_symbols","I44";
;
HDL_POWER"VR_FET_SW_P12V_STBY_PVCCIN_CPU0"
CDS_LIB"mstr_symbols";
"A"8;
%"CAP"
"1","(-5775,1475)","0","mstr_discrete","I45";
;
CDS_SEC"1"
CDS_LOCATION"C4E26"
LOCATION"C4E26"
PART_NUMBER"D97712-011"
PACK_TYPE"0402"
VALUE"1.0UF"
VOLTAGE"16V"
MATERIAL"X6S"
TOLERANCE"10%"
ROOM"PVCCIN_CPU0_PWR_VR"
SEC"1"
SEC_TYPE"0402"
CDS_LIB"mstr_discrete";
"A"
$PN"1"27;
"B"
$PN"2"9;
%"CAP_A"
"1","(-6050,1475)","0","dev_discrete","I46";
;
CDS_LOCATION"C4D49"
PACK_TYPE"0402V"
PART_NUMBER"A36096-030"
LOCATION"C4D49"
VALUE"0.1UF"
TOLERANCE"10%"
VOLTAGE"16V"
MATERIAL"X7R"
SEC"1"
SEC_TYPE"0402V"
CDS_SEC"1"
ROOM"PVCCIN_CPU0_PWR_VR"
CDS_LIB"dev_discrete";
"B"
$PN"2"9;
"A"
$PN"1"8;
%"CAP"
"1","(-6350,1475)","0","mstr_discrete","I47";
;
CDS_SEC"1"
CDS_LOCATION"C4D48"
PART_NUMBER"D97712-011"
MATERIAL"X6S"
PACK_TYPE"0402"
TOLERANCE"10%"
LOCATION"C4D48"
VOLTAGE"16V"
VALUE"1.0UF"
ROOM"PVCCIN_CPU0_PWR_VR"
SEC"1"
SEC_TYPE"0402"
CDS_LIB"mstr_discrete";
"A"
$PN"1"8;
"B"
$PN"2"9;
%"CAP"
"1","(-6625,1475)","0","mstr_discrete","I48";
;
CDS_SEC"1"
PART_NUMBER"C95333-007"
PACK_TYPE"0805"
MATERIAL"X6S"
VOLTAGE"16V"
LOCATION"C6R4"
VALUE"10UF"
TOLERANCE"10%"
ROOM"PVCCIN_CPU0_PWR_VR"
SEC"1"
SEC_TYPE"0805"
CDS_LOCATION"C6R4"
CDS_LIB"mstr_discrete";
"A"
$PN"1"8;
"B"
$PN"2"9;
%"CAP"
"1","(-6900,1475)","0","mstr_discrete","I49";
;
CDS_SEC"1"
PART_NUMBER"C95333-007"
VOLTAGE"16V"
PACK_TYPE"0805"
LOCATION"C6P22"
MATERIAL"X6S"
VALUE"10UF"
TOLERANCE"10%"
ROOM"PVCCIN_CPU0_PWR_VR"
CDS_LOCATION"C6P22"
SEC"1"
SEC_TYPE"0805"
CDS_LIB"mstr_discrete";
"A"
$PN"1"8;
"B"
$PN"2"9;
%"CAP"
"1","(-7175,1475)","0","mstr_discrete","I51";
;
CDS_SEC"1"
LOCATION"C6N8"
VOLTAGE"16V"
TOLERANCE"10%"
MATERIAL"X6S"
PART_NUMBER"C95333-007"
PACK_TYPE"0805"
VALUE"10UF"
SEC_TYPE"0805"
SEC"1"
ROOM"PVCCIN_CPU0_PWR_VR"
CDS_LOCATION"C6N8"
CDS_LIB"mstr_discrete";
"A"
$PN"1"8;
"B"
$PN"2"9;
%"GND"
"1","(-7175,1050)","0","mstr_symbols","I52";
;
SIZE"1B"
VOLTAGE"0"
CDS_LIB"mstr_symbols"
BOM_COST"PROC_VRD_VCCIN_CPU0"
ROOM"PVCCIN_CPU0_PWR_VR"
BODY_TYPE"PLUMBING"
HDL_POWER"GND";
"A\NAC"9;
%"P5V_STBY"
"1","(-4700,2100)","0","mstr_symbols","I59";
;
SIZE"1B"
CDS_LIB"mstr_symbols"
VOLTAGE"5.0V"
BODY_TYPE"PLUMBING"
HDL_POWER"P5V_STBY";
"G\NAC"10;
%"P5V_STBY"
"1","(-4675,4750)","0","mstr_symbols","I60";
;
VOLTAGE"5.0V"
CDS_LIB"mstr_symbols"
SIZE"1B"
BODY_TYPE"PLUMBING"
HDL_POWER"P5V_STBY";
"G\NAC"11;
%"CAP_A"
"1","(-650,3300)","0","dev_discrete","I61";
;
GROUP"PWR_MLCC_CAP"
PACK_TYPE"0603V"
LOCATION"C4E3"
VOLTAGE"4V"
TOLERANCE"20%"
MATERIAL"X6S"
PART_NUMBER"E15431-004"
VALUE"22.0UF"
CDS_SEC"1"
CDS_LOCATION"C4E3"
SEC"1"
SEC_TYPE"0603V"
CDS_LIB"dev_discrete";
"B"
$PN"2"17;
"A"
$PN"1"5;
%"CAP_A"
"1","(-500,750)","0","dev_discrete","I62";
;
GROUP"PWR_MLCC_CAP"
VOLTAGE"4V"
MATERIAL"X6S"
PACK_TYPE"0603V"
VALUE"22.0UF"
LOCATION"C6P16"
TOLERANCE"20%"
PART_NUMBER"E15431-004"
SEC_TYPE"0603V"
CDS_SEC"1"
CDS_LOCATION"C6P16"
SEC"1"
CDS_LIB"dev_discrete";
"B"
$PN"2"3;
"A"
$PN"1"2;
%"IR354XX"
"1","(-3425,3800)","0","mstr_discrete","I63";
;
PART_NUMBER"H73688-001"
MATERIAL"IC"
LOCATION"EU4E1"
VALUE"IR35411"
$SEC"1"
CDS_SEC"1"
PACK_TYPE"SM"
CDS_LOCATION"EU4E1"
CDS_LIB"mstr_discrete";
"TOUT_FLT"
$PN"36"39;
"NC"
$PN"31"0;
"OCSET"
$PN"37"41;
"IOUT"
$PN"38"40;
"SW"
$PN"10"35;
"BOOST"
$PN"33"33;
"REFIN"
$PN"39"31;
"PWM"
$PN"34"28;
"PHASE"
$PN"32"29;
"VIN<0>"
$PN"25"6;
"VCC"
$PN"3"34;
"VIN<1>"
$PN"30"6;
"EN"
$PN"35"11;
"VDRV"
$PN"4"11;
"VOS"
$PN"1"5;
"LGND"
$PN"2"1;
"PGND<1>"
$PN"7"1;
"PGND<2>"
$PN"40"1;
"PGND<0>"
$PN"5"1;
"GL<0>"
$PN"6"42;
"GL<1>"
$PN"41"38;
%"IR354XX"
"1","(-3475,1175)","0","mstr_discrete","I64";
;
PART_NUMBER"H73688-001"
MATERIAL"IC"
LOCATION"EU4D6"
VALUE"IR35411"
PACK_TYPE"SM"
CDS_SEC"1"
$SEC"1"
CDS_LIB"mstr_discrete"
CDS_LOCATION"EU4D6";
"TOUT_FLT"
$PN"36"44;
"NC"
$PN"31"0;
"OCSET"
$PN"37"45;
"IOUT"
$PN"38"30;
"SW"
$PN"10"20;
"BOOST"
$PN"33"43;
"REFIN"
$PN"39"22;
"PWM"
$PN"34"21;
"PHASE"
$PN"32"25;
"VIN<0>"
$PN"25"8;
"VCC"
$PN"3"27;
"VIN<1>"
$PN"30"8;
"EN"
$PN"35"10;
"VDRV"
$PN"4"10;
"VOS"
$PN"1"2;
"LGND"
$PN"2"4;
"PGND<1>"
$PN"7"4;
"PGND<2>"
$PN"40"4;
"PGND<0>"
$PN"5"4;
"GL<0>"
$PN"6"23;
"GL<1>"
$PN"41"24;
%"RES"
"2","(-750,3900)","0","mstr_discrete","I65";
;
CDS_SEC"1"
CDS_LOCATION"R4E22"
PART_NUMBER"G21796-187"
PACK_TYPE"0402"
MATERIAL"EMPTY"
LOCATION"R4E22"
TOLERANCE"1%"
VALUE"68.1K"
WATTAGE"1/16W"
SEC_TYPE"0402"
SEC"1"
CDS_LIB"mstr_discrete";
"A"
$PN"1"41;
"B"
$PN"2"12;
%"GND"
"1","(-750,3700)","0","mstr_symbols","I66";
;
ROOM"PVCCIN_CPU0_PWR_VR"
BOM_COST"PROC_VRD_VCCIN_CPU0"
SIZE"1B"
CDS_LIB"mstr_symbols"
VOLTAGE"0"
BODY_TYPE"PLUMBING"
HDL_POWER"GND";
"A\NAC"12;
%"RES"
"2","(-825,1350)","0","mstr_discrete","I67";
;
CDS_LOCATION"R4E19"
PART_NUMBER"G21796-187"
VALUE"68.1K"
PACK_TYPE"0402"
LOCATION"R4E19"
TOLERANCE"1%"
MATERIAL"EMPTY"
WATTAGE"1/16W"
CDS_LIB"mstr_discrete"
$SEC"1"
CDS_SEC"1";
"A"
$PN"1"45;
"B"
$PN"2"13;
%"GND"
"1","(-825,1150)","0","mstr_symbols","I68";
;
ROOM"PVCCIN_CPU0_PWR_VR"
BOM_COST"PROC_VRD_VCCIN_CPU0"
CDS_LIB"mstr_symbols"
VOLTAGE"0"
SIZE"1B"
BODY_TYPE"PLUMBING"
HDL_POWER"GND";
"A\NAC"13;
%"CAP_A"
"1","(-4125,3300)","0","dev_discrete","I70";
;
CDS_SEC"1"
CDS_LOCATION"CT1"
PART_NUMBER"A36096-030"
PACK_TYPE"0402V"
POP"NOPOP"
VALUE"0.1UF"
LOCATION"CT1"
MATERIAL"X7R"
TOLERANCE"10%"
VOLTAGE"16V"
CDS_LIB"dev_discrete"
ROOM"PVCCIN_CPU0_PWR_VR"
SEC"1"
SEC_TYPE"0402V";
"B"
$PN"2"14;
"A"
$PN"1"31;
%"GND"
"1","(-4125,3050)","0","mstr_symbols","I71";
;
CDS_LIB"mstr_symbols"
VOLTAGE"0"
SIZE"1B"
BOM_COST"PROC_VRD_VCCIN_CPU0"
ROOM"PVCCIN_CPU0_PWR_VR"
BODY_TYPE"PLUMBING"
HDL_POWER"GND";
"A\NAC"14;
%"GND"
"1","(-2350,3625)","0","mstr_symbols","I73";
;
CDS_LIB"mstr_symbols"
ROOM"VDDQ_KLM_PWR_VR"
VOLTAGE"0"
SIZE"1B"
BODY_TYPE"PLUMBING"
HDL_POWER"GND";
"A\NAC"15;
%"GND"
"1","(-2550,2750)","0","mstr_symbols","I77";
;
CDS_LIB"mstr_symbols"
ROOM"PVCCIN_CPU0_PWR_VR"
BOM_COST"PROC_VRD_VCCIN_CPU0"
VOLTAGE"0"
SIZE"1B"
BODY_TYPE"PLUMBING"
HDL_POWER"GND";
"A\NAC"16;
%"CAP"
"1","(-2350,3875)","0","mstr_discrete","I78";
;
CDS_SEC"1"
POP"NOPOP"
LOCATION"CT2"
VALUE"1000PF"
VOLTAGE"50V"
TOLERANCE"10%"
MATERIAL"X7R"
PART_NUMBER"A36096-046"
PACK_TYPE"0402LF"
CDS_LIB"mstr_discrete"
CDS_LOCATION"CT2"
SEC"1"
SEC_TYPE"0402LF"
ROOM"VDDQ_KLM_PWR_VR";
"A"
$PN"1"39;
"B"
$PN"2"15;
%"GND"
"1","(-650,3025)","0","mstr_symbols","I8";
;
CDS_LIB"mstr_symbols"
VOLTAGE"0"
SIZE"1B"
BOM_COST"PROC_VRD_VCCIN_CPU0"
ROOM"PVCCIN_CPU0_PWR_VR"
BODY_TYPE"PLUMBING"
HDL_POWER"GND";
"A\NAC"17;
%"GND"
"1","(-4175,425)","0","mstr_symbols","I80";
;
CDS_LIB"mstr_symbols"
VOLTAGE"0"
SIZE"1B"
BOM_COST"PROC_VRD_VCCIN_CPU0"
ROOM"PVCCIN_CPU0_PWR_VR"
BODY_TYPE"PLUMBING"
HDL_POWER"GND";
"A\NAC"18;
%"CAP_A"
"1","(-4175,675)","0","dev_discrete","I81";
;
CDS_SEC"1"
CDS_LOCATION"CT6"
PART_NUMBER"A36096-030"
LOCATION"CT6"
VALUE"0.1UF"
TOLERANCE"10%"
MATERIAL"X7R"
POP"NOPOP"
VOLTAGE"16V"
PACK_TYPE"0402V"
SEC_TYPE"0402V"
SEC"1"
CDS_LIB"dev_discrete"
ROOM"PVCCIN_CPU0_PWR_VR";
"B"
$PN"2"18;
"A"
$PN"1"22;
%"GND"
"1","(-2550,350)","0","mstr_symbols","I84";
;
CDS_LIB"mstr_symbols"
SIZE"1B"
VOLTAGE"0"
BOM_COST"PROC_VRD_VCCIN_CPU0"
ROOM"PVCCIN_CPU0_PWR_VR"
BODY_TYPE"PLUMBING"
HDL_POWER"GND";
"A\NAC"46;
%"GND"
"1","(-2450,1050)","0","mstr_symbols","I86";
;
CDS_LIB"mstr_symbols"
ROOM"VDDQ_KLM_PWR_VR"
VOLTAGE"0"
SIZE"1B"
BODY_TYPE"PLUMBING"
HDL_POWER"GND";
"A\NAC"19;
%"CAP"
"1","(-2450,1250)","0","mstr_discrete","I87";
;
CDS_SEC"1"
LOCATION"CT4"
VOLTAGE"50V"
TOLERANCE"10%"
MATERIAL"X7R"
VALUE"1000PF"
PACK_TYPE"0402LF"
POP"NOPOP"
PART_NUMBER"A36096-046"
SEC_TYPE"0402LF"
SEC"1"
CDS_LOCATION"CT4"
ROOM"VDDQ_KLM_PWR_VR"
CDS_LIB"mstr_discrete";
"A"
$PN"1"44;
"B"
$PN"2"19;
%"CAP_A"
"1","(-1250,3300)","0","dev_discrete","I9";
;
GROUP"PWR_MLCC_CAP"
VALUE"22.0UF"
PART_NUMBER"E15431-004"
PACK_TYPE"0603V"
MATERIAL"X6S"
TOLERANCE"20%"
VOLTAGE"4V"
LOCATION"C6R7"
CDS_LIB"dev_discrete"
CDS_LOCATION"C6R7"
ROOM"PVCCIN_CPU0_PWR_VR"
CDS_SEC"1"
BOM_COST"PROC_VRD_VCCIN_CPU0"
SEC"1"
SEC_TYPE"0603V";
"B"
$PN"2"17;
"A"
$PN"1"5;
%"CAP"
"1","(-2550,3325)","0","mstr_discrete","I97";
;
CDS_SEC"1"
CDS_LOCATION"CT3"
VALUE"1000PF"
PACK_TYPE"0402LF"
POP"NOPOP"
LOCATION"CT3"
TOLERANCE"10%"
VOLTAGE"50V"
MATERIAL"X7R"
PART_NUMBER"A36096-046"
CDS_LIB"mstr_discrete"
ROOM"VDDQ_KLM_PWR_VR"
SEC"1"
SEC_TYPE"0402LF";
"A"
$PN"1"35;
"B"
$PN"2"37;
%"CAP"
"1","(-2550,825)","0","mstr_discrete","I98";
;
CDS_SEC"1"
CDS_LOCATION"CT5"
MATERIAL"X7R"
LOCATION"CT5"
POP"NOPOP"
VALUE"1000PF"
VOLTAGE"50V"
PACK_TYPE"0402LF"
TOLERANCE"10%"
PART_NUMBER"A36096-046"
SEC_TYPE"0402LF"
SEC"1"
ROOM"VDDQ_KLM_PWR_VR"
CDS_LIB"mstr_discrete";
"A"
$PN"1"20;
"B"
$PN"2"36;
END.
